(kicad_pcb
	(version 20260206)
	(generator "pcbnew")
	(generator_version "10.0")
	(general
		(thickness 1.6)
		(legacy_teardrops no)
	)
	(paper "A4")
	(title_block
		(title "Wiwynn_Tioga_Pass_MB.brd")
		(comment 1 "Tioga Pass / footprints 644-651 of 4770")
	)
	(layers
		(0 "F.Cu" signal "TOP")
		(4 "In1.Cu" signal "L2GND")
		(6 "In2.Cu" signal "L3")
		(8 "In3.Cu" signal "L4GND")
		(10 "In4.Cu" signal "L5")
		(12 "In5.Cu" signal "L6GND")
		(14 "In6.Cu" signal "L7VCC")
		(16 "In7.Cu" signal "L8VCC")
		(18 "In8.Cu" signal "L9GND")
		(20 "In9.Cu" signal "L10")
		(22 "In10.Cu" signal "L11GND")
		(24 "In11.Cu" signal "L12")
		(26 "In12.Cu" signal "L13GND")
		(2 "B.Cu" signal "BOTTOM")
		(9 "F.Adhes" user "F.Adhesive")
		(11 "B.Adhes" user "B.Adhesive")
		(13 "F.Paste" user "Package Geometry/Pastemask Top")
		(15 "B.Paste" user "Package Geometry/Pastemask Bottom")
		(5 "F.SilkS" user "Ref Des/Silkscreen Top")
		(7 "B.SilkS" user "Ref Des/Silkscreen Bottom")
		(1 "F.Mask" user "Board Geometry/Soldermask Top")
		(3 "B.Mask" user "Board Geometry/Soldermask Bottom")
		(17 "Dwgs.User" user "User.Drawings")
		(19 "Cmts.User" user "User.Comments")
		(21 "Eco1.User" user "User.Eco1")
		(23 "Eco2.User" user "User.Eco2")
		(25 "Edge.Cuts" user "Board Geometry/Outline")
		(27 "Margin" user)
		(31 "F.CrtYd" user "Package Geometry/Place Bound Top")
		(29 "B.CrtYd" user "Package Geometry/Place Bound Bottom")
		(35 "F.Fab" user "Ref Des/Assembly Top")
		(33 "B.Fab" user "Ref Des/Assembly Bottom")
	)
	(footprint ""
		(layer "F.Cu")
		(at 464.7057 -24.0157 90)
		(property "Reference" "R8E40"
			(at 0 0 90)
			(layer "F.SilkS")
			(hide yes)
			(effects
				(font
					(size 1.27 1.27)
				)
			)
		)
		(property "Value" ""
			(at 0 0 90)
			(layer "F.Fab")
			(effects
				(font
					(size 1.27 1.27)
				)
			)
		)
		(duplicate_pad_numbers_are_jumpers no)
		(fp_poly
			(pts
				(xy -0.2794 -0.1016) (xy 0.2794 -0.1016) (xy 0.2794 0.9906) (xy -0.2794 0.9906)
			)
			(stroke
				(width 0)
				(type default)
			)
			(fill no)
			(layer "F.CrtYd")
		)
		(fp_line
			(start 0.2794 -0.1016)
			(end -0.2794 -0.1016)
			(stroke
				(width 0.1)
				(type default)
			)
			(layer "F.Fab")
		)
		(fp_line
			(start -0.2794 -0.1016)
			(end -0.2794 0.9906)
			(stroke
				(width 0.1)
				(type default)
			)
			(layer "F.Fab")
		)
		(fp_line
			(start 0.2794 0.9906)
			(end 0.2794 -0.1016)
			(stroke
				(width 0.1)
				(type default)
			)
			(layer "F.Fab")
		)
		(fp_line
			(start -0.2794 0.9906)
			(end 0.2794 0.9906)
			(stroke
				(width 0.1)
				(type default)
			)
			(layer "F.Fab")
		)
		(pad "1" smd rect
			(at 0 0 90)
			(size 0.508 0.508)
			(layers "F.Cu" "F.Mask" "F.Paste")
			(net "P3V3_STBY")
		)
		(pad "2" smd rect
			(at 0 0.889 90)
			(size 0.508 0.508)
			(layers "F.Cu" "F.Mask" "F.Paste")
			(net "VR_P3V3_STBY_EN")
		)
		(zone
			(layer "F.Cu")
			(hatch none 0.5)
			(connect_pads
				(clearance 0)
			)
			(min_thickness 0.25)
			(keepout
				(tracks allowed)
				(vias not_allowed)
				(pads allowed)
				(copperpour not_allowed)
				(footprints allowed)
			)
			(placement
				(enabled no)
				(sheetname "")
			)
			(fill
				(thermal_gap 0.5)
				(thermal_bridge_width 0.5)
				(island_removal_mode 0)
			)
			(polygon
				(pts
					(xy 464.9597 -23.7617) (xy 464.9597 -24.2697) (xy 465.3407 -24.2697) (xy 465.3407 -23.7617)
				)
			)
		)
		(zone
			(layer "F.Cu")
			(hatch none 0.5)
			(connect_pads
				(clearance 0)
			)
			(min_thickness 0.25)
			(keepout
				(tracks not_allowed)
				(vias allowed)
				(pads allowed)
				(copperpour not_allowed)
				(footprints allowed)
			)
			(placement
				(enabled no)
				(sheetname "")
			)
			(fill
				(thermal_gap 0.5)
				(thermal_bridge_width 0.5)
				(island_removal_mode 0)
			)
			(polygon
				(pts
					(xy 465.3407 -23.7617) (xy 465.3407 -24.2697) (xy 464.9597 -24.2697) (xy 464.9597 -23.7617)
				)
			)
		)
	)
	(footprint ""
		(layer "F.Cu")
		(at 388.8359 -154.2161)
		(property "Reference" "C7A40"
			(at 0 0 0)
			(layer "F.SilkS")
			(hide yes)
			(effects
				(font
					(size 1.27 1.27)
				)
			)
		)
		(property "Value" ""
			(at 0 0 0)
			(layer "F.Fab")
			(effects
				(font
					(size 1.27 1.27)
				)
			)
		)
		(duplicate_pad_numbers_are_jumpers no)
		(fp_poly
			(pts
				(xy 0.3048 -0.1016) (xy 0.3048 0.9906) (xy -0.3048 0.9906) (xy -0.3048 -0.1016)
			)
			(stroke
				(width 0)
				(type default)
			)
			(fill no)
			(layer "F.CrtYd")
		)
		(fp_line
			(start -0.3048 -0.1016)
			(end -0.3048 0.9906)
			(stroke
				(width 0.1)
				(type default)
			)
			(layer "F.Fab")
		)
		(fp_line
			(start -0.3048 0.9906)
			(end 0.3048 0.9906)
			(stroke
				(width 0.1)
				(type default)
			)
			(layer "F.Fab")
		)
		(fp_line
			(start 0.3048 -0.1016)
			(end -0.3048 -0.1016)
			(stroke
				(width 0.1)
				(type default)
			)
			(layer "F.Fab")
		)
		(fp_line
			(start 0.3048 0.9906)
			(end 0.3048 -0.1016)
			(stroke
				(width 0.1)
				(type default)
			)
			(layer "F.Fab")
		)
		(pad "1" smd rect
			(at 0 0)
			(size 0.508 0.508)
			(layers "F.Cu" "F.Mask" "F.Paste")
			(net "VR_FET_SW_P12V_STBY_PVDDQ_DEF")
		)
		(pad "2" smd rect
			(at 0 0.889)
			(size 0.508 0.508)
			(layers "F.Cu" "F.Mask" "F.Paste")
			(net "GND")
		)
		(zone
			(layer "F.Cu")
			(hatch none 0.5)
			(connect_pads
				(clearance 0)
			)
			(min_thickness 0.25)
			(keepout
				(tracks allowed)
				(vias not_allowed)
				(pads allowed)
				(copperpour not_allowed)
				(footprints allowed)
			)
			(placement
				(enabled no)
				(sheetname "")
			)
			(fill
				(thermal_gap 0.5)
				(thermal_bridge_width 0.5)
				(island_removal_mode 0)
			)
			(polygon
				(pts
					(xy 388.5819 -153.9621) (xy 389.0899 -153.9621) (xy 389.0899 -153.5811) (xy 388.5819 -153.5811)
				)
			)
		)
		(zone
			(layer "F.Cu")
			(hatch none 0.5)
			(connect_pads
				(clearance 0)
			)
			(min_thickness 0.25)
			(keepout
				(tracks not_allowed)
				(vias allowed)
				(pads allowed)
				(copperpour not_allowed)
				(footprints allowed)
			)
			(placement
				(enabled no)
				(sheetname "")
			)
			(fill
				(thermal_gap 0.5)
				(thermal_bridge_width 0.5)
				(island_removal_mode 0)
			)
			(polygon
				(pts
					(xy 388.5819 -153.5811) (xy 389.0899 -153.5811) (xy 389.0899 -153.9621) (xy 388.5819 -153.9621)
				)
			)
		)
	)
	(footprint ""
		(layer "F.Cu")
		(at 10.795 -15.875)
		(property "Reference" "L1F2"
			(at 3.378708 -4.251706 0)
			(unlocked yes)
			(layer "F.SilkS")
			(effects
				(font
					(size 0.4064 0.254)
					(thickness 0.1524)
				)
			)
		)
		(property "Value" ""
			(at 0 0 0)
			(layer "F.Fab")
			(effects
				(font
					(size 1.27 1.27)
				)
			)
		)
		(duplicate_pad_numbers_are_jumpers no)
		(fp_line
			(start -1.1303 -3.199892)
			(end 8.3693 -3.199892)
			(stroke
				(width 0.1524)
				(type default)
			)
			(layer "F.SilkS")
		)
		(fp_line
			(start -1.1303 -1.6637)
			(end -1.1303 -3.199892)
			(stroke
				(width 0.1524)
				(type default)
			)
			(layer "F.SilkS")
		)
		(fp_line
			(start -1.1303 3.199892)
			(end -1.1303 1.6637)
			(stroke
				(width 0.1524)
				(type default)
			)
			(layer "F.SilkS")
		)
		(fp_line
			(start 8.3693 -3.199892)
			(end 8.3693 -1.6637)
			(stroke
				(width 0.1524)
				(type default)
			)
			(layer "F.SilkS")
		)
		(fp_line
			(start 8.3693 1.6637)
			(end 8.3693 3.199892)
			(stroke
				(width 0.1524)
				(type default)
			)
			(layer "F.SilkS")
		)
		(fp_line
			(start 8.3693 3.199892)
			(end -1.1303 3.199892)
			(stroke
				(width 0.1524)
				(type default)
			)
			(layer "F.SilkS")
		)
		(fp_rect
			(start -1.1303 3.199892)
			(end 8.3693 -3.199892)
			(stroke
				(width 0)
				(type default)
			)
			(fill no)
			(layer "F.CrtYd")
		)
		(fp_line
			(start -1.1303 -3.199892)
			(end 8.3693 -3.199892)
			(stroke
				(width 0.1)
				(type default)
			)
			(layer "F.Fab")
		)
		(fp_line
			(start -1.1303 3.199892)
			(end -1.1303 -3.199892)
			(stroke
				(width 0.1)
				(type default)
			)
			(layer "F.Fab")
		)
		(fp_line
			(start 8.3693 -3.199892)
			(end 8.3693 3.199892)
			(stroke
				(width 0.1)
				(type default)
			)
			(layer "F.Fab")
		)
		(fp_line
			(start 8.3693 3.199892)
			(end -1.1303 3.199892)
			(stroke
				(width 0.1)
				(type default)
			)
			(layer "F.Fab")
		)
		(pad "1" smd rect
			(at 0 0)
			(size 3.683 2.667)
			(layers "F.Cu" "F.Mask" "F.Paste")
			(net "VR_PVDDQ_GHJ_PH2_SW")
		)
		(pad "2" smd rect
			(at 7.239 0)
			(size 3.683 2.667)
			(layers "F.Cu" "F.Mask" "F.Paste")
			(net "PVDDQ_GHJ")
		)
	)
	(footprint ""
		(layer "F.Cu")
		(at 384.4798 -0.254)
		(property "Reference" "R7G15"
			(at 0 0 0)
			(layer "F.SilkS")
			(hide yes)
			(effects
				(font
					(size 1.27 1.27)
				)
			)
		)
		(property "Value" ""
			(at 0 0 0)
			(layer "F.Fab")
			(effects
				(font
					(size 1.27 1.27)
				)
			)
		)
		(duplicate_pad_numbers_are_jumpers no)
		(fp_poly
			(pts
				(xy -0.2794 -0.1016) (xy 0.2794 -0.1016) (xy 0.2794 0.9906) (xy -0.2794 0.9906)
			)
			(stroke
				(width 0)
				(type default)
			)
			(fill no)
			(layer "F.CrtYd")
		)
		(fp_line
			(start -0.2794 -0.1016)
			(end -0.2794 0.9906)
			(stroke
				(width 0.1)
				(type default)
			)
			(layer "F.Fab")
		)
		(fp_line
			(start -0.2794 0.9906)
			(end 0.2794 0.9906)
			(stroke
				(width 0.1)
				(type default)
			)
			(layer "F.Fab")
		)
		(fp_line
			(start 0.2794 -0.1016)
			(end -0.2794 -0.1016)
			(stroke
				(width 0.1)
				(type default)
			)
			(layer "F.Fab")
		)
		(fp_line
			(start 0.2794 0.9906)
			(end 0.2794 -0.1016)
			(stroke
				(width 0.1)
				(type default)
			)
			(layer "F.Fab")
		)
		(pad "1" smd rect
			(at 0 0)
			(size 0.508 0.508)
			(layers "F.Cu" "F.Mask" "F.Paste")
			(net "JTAG_PCH_PLD_TDO")
		)
		(pad "2" smd rect
			(at 0 0.889)
			(size 0.508 0.508)
			(layers "F.Cu" "F.Mask" "F.Paste")
			(net "JTAG_TDO")
		)
		(zone
			(layer "F.Cu")
			(hatch none 0.5)
			(connect_pads
				(clearance 0)
			)
			(min_thickness 0.25)
			(keepout
				(tracks allowed)
				(vias not_allowed)
				(pads allowed)
				(copperpour not_allowed)
				(footprints allowed)
			)
			(placement
				(enabled no)
				(sheetname "")
			)
			(fill
				(thermal_gap 0.5)
				(thermal_bridge_width 0.5)
				(island_removal_mode 0)
			)
			(polygon
				(pts
					(xy 384.2258 0) (xy 384.7338 0) (xy 384.7338 0.381) (xy 384.2258 0.381)
				)
			)
		)
		(zone
			(layer "F.Cu")
			(hatch none 0.5)
			(connect_pads
				(clearance 0)
			)
			(min_thickness 0.25)
			(keepout
				(tracks not_allowed)
				(vias allowed)
				(pads allowed)
				(copperpour not_allowed)
				(footprints allowed)
			)
			(placement
				(enabled no)
				(sheetname "")
			)
			(fill
				(thermal_gap 0.5)
				(thermal_bridge_width 0.5)
				(island_removal_mode 0)
			)
			(polygon
				(pts
					(xy 384.2258 0.381) (xy 384.7338 0.381) (xy 384.7338 0) (xy 384.2258 0)
				)
			)
		)
	)
	(footprint ""
		(layer "F.Cu")
		(at 401.13966 -152.66416 -90)
		(property "Reference" "R8W8"
			(at -0.8382 -0.67818 270)
			(unlocked yes)
			(layer "F.SilkS")
			(effects
				(font
					(size 0.4064 0.254)
					(thickness 0.1524)
				)
				(justify left)
			)
		)
		(property "Value" ""
			(at 0 0 270)
			(layer "F.Fab")
			(effects
				(font
					(size 1.27 1.27)
				)
			)
		)
		(duplicate_pad_numbers_are_jumpers no)
		(fp_poly
			(pts
				(xy -0.2794 -0.1016) (xy 0.2794 -0.1016) (xy 0.2794 0.9906) (xy -0.2794 0.9906)
			)
			(stroke
				(width 0)
				(type default)
			)
			(fill no)
			(layer "F.CrtYd")
		)
		(fp_line
			(start -0.2794 0.9906)
			(end 0.2794 0.9906)
			(stroke
				(width 0.1)
				(type default)
			)
			(layer "F.Fab")
		)
		(fp_line
			(start 0.2794 0.9906)
			(end 0.2794 -0.1016)
			(stroke
				(width 0.1)
				(type default)
			)
			(layer "F.Fab")
		)
		(fp_line
			(start -0.2794 -0.1016)
			(end -0.2794 0.9906)
			(stroke
				(width 0.1)
				(type default)
			)
			(layer "F.Fab")
		)
		(fp_line
			(start 0.2794 -0.1016)
			(end -0.2794 -0.1016)
			(stroke
				(width 0.1)
				(type default)
			)
			(layer "F.Fab")
		)
		(pad "1" smd rect
			(at 0 0 270)
			(size 0.508 0.508)
			(layers "F.Cu" "F.Mask" "F.Paste")
			(net "P3V3_STBY")
		)
		(pad "2" smd rect
			(at 0 0.889 270)
			(size 0.508 0.508)
			(layers "F.Cu" "F.Mask" "F.Paste")
			(net "PU_PVNN_PCH_PINALRT_N")
		)
		(zone
			(layer "F.Cu")
			(hatch none 0.5)
			(connect_pads
				(clearance 0)
			)
			(min_thickness 0.25)
			(keepout
				(tracks not_allowed)
				(vias allowed)
				(pads allowed)
				(copperpour not_allowed)
				(footprints allowed)
			)
			(placement
				(enabled no)
				(sheetname "")
			)
			(fill
				(thermal_gap 0.5)
				(thermal_bridge_width 0.5)
				(island_removal_mode 0)
			)
			(polygon
				(pts
					(xy 400.50466 -152.91816) (xy 400.50466 -152.41016) (xy 400.88566 -152.41016) (xy 400.88566 -152.91816)
				)
			)
		)
		(zone
			(layer "F.Cu")
			(hatch none 0.5)
			(connect_pads
				(clearance 0)
			)
			(min_thickness 0.25)
			(keepout
				(tracks allowed)
				(vias not_allowed)
				(pads allowed)
				(copperpour not_allowed)
				(footprints allowed)
			)
			(placement
				(enabled no)
				(sheetname "")
			)
			(fill
				(thermal_gap 0.5)
				(thermal_bridge_width 0.5)
				(island_removal_mode 0)
			)
			(polygon
				(pts
					(xy 400.88566 -152.91816) (xy 400.88566 -152.41016) (xy 400.50466 -152.41016) (xy 400.50466 -152.91816)
				)
			)
		)
	)
	(footprint ""
		(layer "F.Cu")
		(at 362.9152 -133.096 180)
		(property "Reference" "R7B4"
			(at 0 0 180)
			(layer "F.SilkS")
			(hide yes)
			(effects
				(font
					(size 1.27 1.27)
				)
			)
		)
		(property "Value" ""
			(at 0 0 180)
			(layer "F.Fab")
			(effects
				(font
					(size 1.27 1.27)
				)
			)
		)
		(duplicate_pad_numbers_are_jumpers no)
		(fp_poly
			(pts
				(xy -0.2794 -0.1016) (xy 0.2794 -0.1016) (xy 0.2794 0.9906) (xy -0.2794 0.9906)
			)
			(stroke
				(width 0)
				(type default)
			)
			(fill no)
			(layer "F.CrtYd")
		)
		(fp_line
			(start 0.2794 0.9906)
			(end 0.2794 -0.1016)
			(stroke
				(width 0.1)
				(type default)
			)
			(layer "F.Fab")
		)
		(fp_line
			(start 0.2794 -0.1016)
			(end -0.2794 -0.1016)
			(stroke
				(width 0.1)
				(type default)
			)
			(layer "F.Fab")
		)
		(fp_line
			(start -0.2794 0.9906)
			(end 0.2794 0.9906)
			(stroke
				(width 0.1)
				(type default)
			)
			(layer "F.Fab")
		)
		(fp_line
			(start -0.2794 -0.1016)
			(end -0.2794 0.9906)
			(stroke
				(width 0.1)
				(type default)
			)
			(layer "F.Fab")
		)
		(pad "1" smd rect
			(at 0 0 180)
			(size 0.508 0.508)
			(layers "F.Cu" "F.Mask" "F.Paste")
			(net "P3V3_STBY")
		)
		(pad "2" smd rect
			(at 0 0.889 180)
			(size 0.508 0.508)
			(layers "F.Cu" "F.Mask" "F.Paste")
			(net "IRQ_PVDDQ_DEF_VRHOT_LVT3_R_N")
		)
		(zone
			(layer "F.Cu")
			(hatch none 0.5)
			(connect_pads
				(clearance 0)
			)
			(min_thickness 0.25)
			(keepout
				(tracks not_allowed)
				(vias allowed)
				(pads allowed)
				(copperpour not_allowed)
				(footprints allowed)
			)
			(placement
				(enabled no)
				(sheetname "")
			)
			(fill
				(thermal_gap 0.5)
				(thermal_bridge_width 0.5)
				(island_removal_mode 0)
			)
			(polygon
				(pts
					(xy 363.1692 -133.731) (xy 362.6612 -133.731) (xy 362.6612 -133.35) (xy 363.1692 -133.35)
				)
			)
		)
		(zone
			(layer "F.Cu")
			(hatch none 0.5)
			(connect_pads
				(clearance 0)
			)
			(min_thickness 0.25)
			(keepout
				(tracks allowed)
				(vias not_allowed)
				(pads allowed)
				(copperpour not_allowed)
				(footprints allowed)
			)
			(placement
				(enabled no)
				(sheetname "")
			)
			(fill
				(thermal_gap 0.5)
				(thermal_bridge_width 0.5)
				(island_removal_mode 0)
			)
			(polygon
				(pts
					(xy 363.1692 -133.35) (xy 362.6612 -133.35) (xy 362.6612 -133.731) (xy 363.1692 -133.731)
				)
			)
		)
	)
	(footprint ""
		(layer "F.Cu")
		(at 490.148372 -55.87365)
		(property "Reference" "C30W4"
			(at 0 0 0)
			(layer "F.SilkS")
			(hide yes)
			(effects
				(font
					(size 1.27 1.27)
				)
			)
		)
		(property "Value" "*"
			(at -0.0762 -6.2357 0)
			(unlocked yes)
			(layer "F.Fab")
			(hide yes)
			(effects
				(font
					(size 1.27 1.016)
					(thickness 0.1524)
				)
			)
		)
		(property "Device Type" "SC22U16V5MX-4-GP_SMD-BCG5-SC22A"
			(at -0.0762 -8.2677 0)
			(unlocked yes)
			(layer "F.Fab")
			(hide yes)
			(effects
				(font
					(size 1.27 1.016)
					(thickness 0.1524)
				)
			)
		)
		(duplicate_pad_numbers_are_jumpers no)
		(fp_line
			(start 0.635 0)
			(end -0.635 0)
			(stroke
				(width 0.508)
				(type default)
			)
			(layer "F.SilkS")
		)
		(fp_rect
			(start -0.9652 1.778)
			(end 0.9652 -1.778)
			(stroke
				(width 0)
				(type default)
			)
			(fill no)
			(layer "F.CrtYd")
		)
		(fp_poly
			(pts
				(xy -0.9652 -1.778) (xy 0.9652 -1.778) (xy 0.9652 1.778) (xy -0.9652 1.778)
			)
			(stroke
				(width 0)
				(type default)
			)
			(fill no)
			(layer "F.Fab")
		)
		(pad "1" smd rect
			(at 0 -0.9652)
			(size 1.397 1.143)
			(layers "F.Cu" "F.Mask" "F.Paste")
			(net "P5V_STBY_USBC")
		)
		(pad "2" smd rect
			(at 0 0.9652)
			(size 1.397 1.143)
			(layers "F.Cu" "F.Mask" "F.Paste")
			(net "GND")
		)
	)
	(footprint ""
		(layer "F.Cu")
		(at 259.49402 -12.961112 90)
		(property "Reference" "C5G9"
			(at 0 0 90)
			(layer "F.SilkS")
			(hide yes)
			(effects
				(font
					(size 1.27 1.27)
				)
			)
		)
		(property "Value" ""
			(at 0 0 90)
			(layer "F.Fab")
			(effects
				(font
					(size 1.27 1.27)
				)
			)
		)
		(duplicate_pad_numbers_are_jumpers no)
		(fp_rect
			(start -0.7239 -0.2159)
			(end 0.7239 1.9939)
			(stroke
				(width 0)
				(type default)
			)
			(fill no)
			(layer "F.CrtYd")
		)
		(fp_line
			(start 0.7239 -0.2159)
			(end -0.7239 -0.2159)
			(stroke
				(width 0.1)
				(type default)
			)
			(layer "F.Fab")
		)
		(fp_line
			(start -0.7239 -0.2159)
			(end -0.7239 1.9939)
			(stroke
				(width 0.1)
				(type default)
			)
			(layer "F.Fab")
		)
		(fp_line
			(start 0.7239 1.9939)
			(end 0.7239 -0.2159)
			(stroke
				(width 0.1)
				(type default)
			)
			(layer "F.Fab")
		)
		(fp_line
			(start -0.7239 1.9939)
			(end 0.7239 1.9939)
			(stroke
				(width 0.1)
				(type default)
			)
			(layer "F.Fab")
		)
		(pad "1" smd rect
			(at 0 0 90)
			(size 1.27 1.016)
			(layers "F.Cu" "F.Mask" "F.Paste")
			(net "PVDDQ_ABC")
		)
		(pad "2" smd rect
			(at 0 1.778 90)
			(size 1.27 1.016)
			(layers "F.Cu" "F.Mask" "F.Paste")
			(net "GND")
		)
		(zone
			(layer "F.Cu")
			(hatch none 0.5)
			(connect_pads
				(clearance 0)
			)
			(min_thickness 0.25)
			(keepout
				(tracks not_allowed)
				(vias allowed)
				(pads allowed)
				(copperpour not_allowed)
				(footprints allowed)
			)
			(placement
				(enabled no)
				(sheetname "")
			)
			(fill
				(thermal_gap 0.5)
				(thermal_bridge_width 0.5)
				(island_removal_mode 0)
			)
			(polygon
				(pts
					(xy 260.00202 -12.326112) (xy 260.76402 -12.326112) (xy 260.76402 -13.596112) (xy 260.00202 -13.596112)
				)
			)
		)
	)
)
